(kicad_pcb
	(version 20260206)
	(generator "pcbnew")
	(generator_version "10.0")
	(general
		(thickness 1.6)
		(legacy_teardrops no)
	)
	(paper "A4")
	(title_block
		(title "Bryce Canyon_IOM_IOC_16318-2_OCP.brd")
		(comment 1 "Bryce Canyon / footprints 1593-1601 of 1605")
	)
	(layers
		(0 "F.Cu" signal "TOP")
		(4 "In1.Cu" signal "L2GND")
		(6 "In2.Cu" signal "L3")
		(8 "In3.Cu" signal "L4VCC")
		(10 "In4.Cu" signal "L5VCC")
		(12 "In5.Cu" signal "L6")
		(14 "In6.Cu" signal "L7GND")
		(2 "B.Cu" signal "BOTTOM")
		(9 "F.Adhes" user "F.Adhesive")
		(11 "B.Adhes" user "B.Adhesive")
		(13 "F.Paste" user "Package Geometry/Pastemask Top")
		(15 "B.Paste" user "Package Geometry/Pastemask Bottom")
		(5 "F.SilkS" user "Ref Des/Silkscreen Top")
		(7 "B.SilkS" user "Ref Des/Silkscreen Bottom")
		(1 "F.Mask" user "Board Geometry/Soldermask Top")
		(3 "B.Mask" user "Board Geometry/Soldermask Bottom")
		(17 "Dwgs.User" user "User.Drawings")
		(19 "Cmts.User" user "User.Comments")
		(21 "Eco1.User" user "User.Eco1")
		(23 "Eco2.User" user "User.Eco2")
		(25 "Edge.Cuts" user "Board Geometry/Outline")
		(27 "Margin" user)
		(31 "F.CrtYd" user "Package Geometry/Place Bound Top")
		(29 "B.CrtYd" user "Package Geometry/Place Bound Bottom")
		(35 "F.Fab" user "Ref Des/Assembly Top")
		(33 "B.Fab" user "Ref Des/Assembly Bottom")
	)
	(footprint ""
		(layer "B.Cu")
		(at 177.488342 -70.763638)
		(property "Reference" "TP160"
			(at 0 0 0)
			(layer "B.SilkS")
			(hide yes)
			(effects
				(font
					(size 1.27 1.27)
				)
				(justify mirror)
			)
		)
		(property "Value" "TPAD28-2-GP"
			(at 0.0127 -1.6637 0)
			(unlocked yes)
			(layer "B.Fab")
			(hide yes)
			(effects
				(font
					(size 1.016 1.016)
					(thickness 0.1524)
				)
				(justify mirror)
			)
		)
		(property "Device Type" "TPAD28"
			(at 0.0127 -3.1877 0)
			(unlocked yes)
			(layer "B.Fab")
			(hide yes)
			(effects
				(font
					(size 1.016 1.016)
					(thickness 0.1524)
				)
				(justify mirror)
			)
		)
		(duplicate_pad_numbers_are_jumpers no)
		(fp_poly
			(pts
				(arc
					(start 0.3556 0)
					(mid -0.3556 0)
					(end 0.3556 0)
				)
			)
			(stroke
				(width 0)
				(type default)
			)
			(fill no)
			(layer "B.CrtYd")
		)
		(fp_poly
			(pts
				(arc
					(start 0.6096 0)
					(mid -0.6096 0)
					(end 0.6096 0)
				)
			)
			(stroke
				(width 0)
				(type default)
			)
			(fill no)
			(layer "B.Fab")
		)
		(pad "1" smd circle
			(at 0 0 180)
			(size 0.7112 0.7112)
			(layers "B.Cu" "B.Mask" "B.Paste")
			(net "SPARE4")
		)
	)
	(footprint ""
		(layer "B.Cu")
		(at 198.4248 -71.11492 90)
		(property "Reference" "C369"
			(at 0 0 90)
			(layer "B.SilkS")
			(hide yes)
			(effects
				(font
					(size 1.27 1.27)
				)
				(justify mirror)
			)
		)
		(property "Value" "SCD1U6D3V1KX-GP"
			(at 2.8321 -1.7399 90)
			(unlocked yes)
			(layer "B.Fab")
			(hide yes)
			(effects
				(font
					(size 1.016 1.016)
					(thickness 0.1524)
				)
				(justify mirror)
			)
		)
		(property "Device Type" "C0201H13"
			(at 2.8321 -3.2639 90)
			(unlocked yes)
			(layer "B.Fab")
			(hide yes)
			(effects
				(font
					(size 1.016 1.016)
					(thickness 0.1524)
				)
				(justify mirror)
			)
		)
		(duplicate_pad_numbers_are_jumpers no)
		(fp_rect
			(start 0.2794 0.6477)
			(end -0.2794 -0.6477)
			(stroke
				(width 0)
				(type default)
			)
			(fill no)
			(layer "B.CrtYd")
		)
		(fp_rect
			(start 0.2794 0.6477)
			(end -0.2794 -0.6477)
			(stroke
				(width 0)
				(type default)
			)
			(fill no)
			(layer "B.Fab")
		)
		(pad "1" smd custom
			(at 0 -0.2794 270)
			(size 0.0762 0.0762)
			(layers "B.Cu" "B.Mask" "B.Paste")
			(net "PCE_AVDD")
			(options
				(clearance outline)
				(anchor circle)
			)
			(primitives
				(gr_poly
					(pts
						(arc
							(start 0.1524 0.127)
							(mid 0.137521 0.162921)
							(end 0.1016 0.1778)
						)
						(arc
							(start -0.1016 0.1778)
							(mid -0.137521 0.162921)
							(end -0.1524 0.127)
						)
						(arc
							(start -0.1524 -0.127)
							(mid -0.137521 -0.162921)
							(end -0.1016 -0.1778)
						)
						(arc
							(start 0.1016 -0.1778)
							(mid 0.137521 -0.162921)
							(end 0.1524 -0.127)
						)
					)
					(width 0)
					(fill yes)
				)
			)
		)
		(pad "2" smd custom
			(at 0 0.2794 270)
			(size 0.0762 0.0762)
			(layers "B.Cu" "B.Mask" "B.Paste")
			(net "GND")
			(options
				(clearance outline)
				(anchor circle)
			)
			(primitives
				(gr_poly
					(pts
						(arc
							(start 0.1524 0.127)
							(mid 0.137521 0.162921)
							(end 0.1016 0.1778)
						)
						(arc
							(start -0.1016 0.1778)
							(mid -0.137521 0.162921)
							(end -0.1524 0.127)
						)
						(arc
							(start -0.1524 -0.127)
							(mid -0.137521 -0.162921)
							(end -0.1016 -0.1778)
						)
						(arc
							(start 0.1016 -0.1778)
							(mid 0.137521 -0.162921)
							(end 0.1524 -0.127)
						)
					)
					(width 0)
					(fill yes)
				)
			)
		)
	)
	(footprint ""
		(layer "B.Cu")
		(at 210.5152 -60.3504)
		(property "Reference" "R630"
			(at 0 0 0)
			(layer "B.SilkS")
			(hide yes)
			(effects
				(font
					(size 1.27 1.27)
				)
				(justify mirror)
			)
		)
		(property "Value" "4K7R2F-GP"
			(at -0.064008 -3.993896 0)
			(unlocked yes)
			(layer "B.Fab")
			(hide yes)
			(effects
				(font
					(size 1.016 1.016)
					(thickness 0.1524)
				)
				(justify mirror)
			)
		)
		(property "Device Type" "R402H16"
			(at -0.064008 -5.517896 0)
			(unlocked yes)
			(layer "B.Fab")
			(hide yes)
			(effects
				(font
					(size 1.016 1.016)
					(thickness 0.1524)
				)
				(justify mirror)
			)
		)
		(duplicate_pad_numbers_are_jumpers no)
		(fp_line
			(start -0.508 -0.9398)
			(end 0.508 -0.9398)
			(stroke
				(width 0.1524)
				(type default)
			)
			(layer "B.SilkS")
		)
		(fp_line
			(start 0.508 -0.9398)
			(end 0.508 0.9398)
			(stroke
				(width 0.1524)
				(type default)
			)
			(layer "B.SilkS")
		)
		(fp_rect
			(start 0.508 0.9398)
			(end -0.508 -0.9398)
			(stroke
				(width 0)
				(type default)
			)
			(fill no)
			(layer "B.CrtYd")
		)
		(fp_rect
			(start 0.508 0.9398)
			(end -0.508 -0.9398)
			(stroke
				(width 0)
				(type default)
			)
			(fill no)
			(layer "B.Fab")
		)
		(pad "1" smd custom
			(at 0 -0.4445 180)
			(size 0.1397 0.1397)
			(layers "B.Cu" "B.Mask" "B.Paste")
			(net "P1V8")
			(options
				(clearance outline)
				(anchor circle)
			)
			(primitives
				(gr_poly
					(pts
						(arc
							(start -0.1778 0.2794)
							(mid -0.249642 0.249642)
							(end -0.2794 0.1778)
						)
						(arc
							(start -0.2794 -0.1778)
							(mid -0.249642 -0.249642)
							(end -0.1778 -0.2794)
						)
						(arc
							(start 0.1778 -0.2794)
							(mid 0.249642 -0.249642)
							(end 0.2794 -0.1778)
						)
						(arc
							(start 0.2794 0.1778)
							(mid 0.249642 0.249642)
							(end 0.1778 0.2794)
						)
					)
					(width 0)
					(fill yes)
				)
			)
		)
		(pad "2" smd custom
			(at 0 0.4445 180)
			(size 0.1397 0.1397)
			(layers "B.Cu" "B.Mask" "B.Paste")
			(net "ICE1_TDI")
			(options
				(clearance outline)
				(anchor circle)
			)
			(primitives
				(gr_poly
					(pts
						(arc
							(start -0.1778 0.2794)
							(mid -0.249642 0.249642)
							(end -0.2794 0.1778)
						)
						(arc
							(start -0.2794 -0.1778)
							(mid -0.249642 -0.249642)
							(end -0.1778 -0.2794)
						)
						(arc
							(start 0.1778 -0.2794)
							(mid 0.249642 -0.249642)
							(end 0.2794 -0.1778)
						)
						(arc
							(start 0.2794 0.1778)
							(mid 0.249642 0.249642)
							(end 0.1778 0.2794)
						)
					)
					(width 0)
					(fill yes)
				)
			)
		)
	)
	(footprint ""
		(layer "B.Cu")
		(at 197.5866 -46.2788 90)
		(property "Reference" "R683"
			(at 0 0 90)
			(layer "B.SilkS")
			(hide yes)
			(effects
				(font
					(size 1.27 1.27)
				)
				(justify mirror)
			)
		)
		(property "Value" "10R2F-L-GP"
			(at -0.064008 -3.993896 90)
			(unlocked yes)
			(layer "B.Fab")
			(hide yes)
			(effects
				(font
					(size 1.016 1.016)
					(thickness 0.1524)
				)
				(justify mirror)
			)
		)
		(property "Device Type" "R402H14"
			(at -0.064008 -5.517896 90)
			(unlocked yes)
			(layer "B.Fab")
			(hide yes)
			(effects
				(font
					(size 1.016 1.016)
					(thickness 0.1524)
				)
				(justify mirror)
			)
		)
		(duplicate_pad_numbers_are_jumpers no)
		(fp_line
			(start 0.508 -0.9398)
			(end 0.508 0.9398)
			(stroke
				(width 0.1524)
				(type default)
			)
			(layer "B.SilkS")
		)
		(fp_line
			(start -0.508 -0.9398)
			(end 0.508 -0.9398)
			(stroke
				(width 0.1524)
				(type default)
			)
			(layer "B.SilkS")
		)
		(fp_rect
			(start 0.508 0.9398)
			(end -0.508 -0.9398)
			(stroke
				(width 0)
				(type default)
			)
			(fill no)
			(layer "B.CrtYd")
		)
		(fp_rect
			(start 0.508 0.9398)
			(end -0.508 -0.9398)
			(stroke
				(width 0)
				(type default)
			)
			(fill no)
			(layer "B.Fab")
		)
		(pad "1" smd custom
			(at 0 -0.4445 270)
			(size 0.1397 0.1397)
			(layers "B.Cu" "B.Mask" "B.Paste")
			(net "P1V8")
			(options
				(clearance outline)
				(anchor circle)
			)
			(primitives
				(gr_poly
					(pts
						(arc
							(start -0.1778 0.2794)
							(mid -0.249642 0.249642)
							(end -0.2794 0.1778)
						)
						(arc
							(start -0.2794 -0.1778)
							(mid -0.249642 -0.249642)
							(end -0.1778 -0.2794)
						)
						(arc
							(start 0.1778 -0.2794)
							(mid 0.249642 -0.249642)
							(end 0.2794 -0.1778)
						)
						(arc
							(start 0.2794 0.1778)
							(mid 0.249642 0.249642)
							(end 0.1778 0.2794)
						)
					)
					(width 0)
					(fill yes)
				)
			)
		)
		(pad "2" smd custom
			(at 0 0.4445 270)
			(size 0.1397 0.1397)
			(layers "B.Cu" "B.Mask" "B.Paste")
			(net "VDDA_SAS_REF_CLK")
			(options
				(clearance outline)
				(anchor circle)
			)
			(primitives
				(gr_poly
					(pts
						(arc
							(start -0.1778 0.2794)
							(mid -0.249642 0.249642)
							(end -0.2794 0.1778)
						)
						(arc
							(start -0.2794 -0.1778)
							(mid -0.249642 -0.249642)
							(end -0.1778 -0.2794)
						)
						(arc
							(start 0.1778 -0.2794)
							(mid 0.249642 -0.249642)
							(end 0.2794 -0.1778)
						)
						(arc
							(start 0.2794 0.1778)
							(mid 0.249642 0.249642)
							(end 0.1778 0.2794)
						)
					)
					(width 0)
					(fill yes)
				)
			)
		)
	)
	(footprint ""
		(layer "B.Cu")
		(at 34.8234 -150.8252 180)
		(property "Reference" "C94"
			(at 0 0 0)
			(layer "B.SilkS")
			(hide yes)
			(effects
				(font
					(size 1.27 1.27)
				)
				(justify mirror)
			)
		)
		(property "Value" "SC100P50V2JN-3GP"
			(at -1.1811 -2.7051 180)
			(unlocked yes)
			(layer "B.Fab")
			(hide yes)
			(effects
				(font
					(size 1.016 1.016)
					(thickness 0.1524)
				)
				(justify mirror)
			)
		)
		(property "Device Type" "C402H22"
			(at -1.1811 -4.2291 180)
			(unlocked yes)
			(layer "B.Fab")
			(hide yes)
			(effects
				(font
					(size 1.016 1.016)
					(thickness 0.1524)
				)
				(justify mirror)
			)
		)
		(duplicate_pad_numbers_are_jumpers no)
		(fp_rect
			(start 0.4318 0.9525)
			(end -0.4318 -0.9525)
			(stroke
				(width 0)
				(type default)
			)
			(fill no)
			(layer "B.CrtYd")
		)
		(fp_rect
			(start 0.4318 0.9525)
			(end -0.4318 -0.9525)
			(stroke
				(width 0)
				(type default)
			)
			(fill no)
			(layer "B.Fab")
		)
		(pad "1" smd custom
			(at 0 -0.4445)
			(size 0.1524 0.1524)
			(layers "B.Cu" "B.Mask" "B.Paste")
			(net "MPLLAV33")
			(options
				(clearance outline)
				(anchor circle)
			)
			(primitives
				(gr_poly
					(pts
						(arc
							(start 0.3048 0.2032)
							(mid 0.275042 0.275042)
							(end 0.2032 0.3048)
						)
						(arc
							(start -0.2032 0.3048)
							(mid -0.275042 0.275042)
							(end -0.3048 0.2032)
						)
						(arc
							(start -0.3048 -0.2032)
							(mid -0.275042 -0.275042)
							(end -0.2032 -0.3048)
						)
						(arc
							(start 0.2032 -0.3048)
							(mid 0.275042 -0.275042)
							(end 0.3048 -0.2032)
						)
					)
					(width 0)
					(fill yes)
				)
			)
		)
		(pad "2" smd custom
			(at 0 0.4445)
			(size 0.1524 0.1524)
			(layers "B.Cu" "B.Mask" "B.Paste")
			(net "GND")
			(options
				(clearance outline)
				(anchor circle)
			)
			(primitives
				(gr_poly
					(pts
						(arc
							(start 0.3048 0.2032)
							(mid 0.275042 0.275042)
							(end 0.2032 0.3048)
						)
						(arc
							(start -0.2032 0.3048)
							(mid -0.275042 0.275042)
							(end -0.3048 0.2032)
						)
						(arc
							(start -0.3048 -0.2032)
							(mid -0.275042 -0.275042)
							(end -0.2032 -0.3048)
						)
						(arc
							(start 0.2032 -0.3048)
							(mid 0.275042 -0.275042)
							(end 0.3048 -0.2032)
						)
					)
					(width 0)
					(fill yes)
				)
			)
		)
	)
	(footprint ""
		(layer "B.Cu")
		(at 179.4764 -77.1652)
		(property "Reference" "TP106"
			(at 0 0 0)
			(layer "B.SilkS")
			(hide yes)
			(effects
				(font
					(size 1.27 1.27)
				)
				(justify mirror)
			)
		)
		(property "Value" "TPAD28-2-GP"
			(at 0.0127 -1.6637 0)
			(unlocked yes)
			(layer "B.Fab")
			(hide yes)
			(effects
				(font
					(size 1.016 1.016)
					(thickness 0.1524)
				)
				(justify mirror)
			)
		)
		(property "Device Type" "TPAD28"
			(at 0.0127 -3.1877 0)
			(unlocked yes)
			(layer "B.Fab")
			(hide yes)
			(effects
				(font
					(size 1.016 1.016)
					(thickness 0.1524)
				)
				(justify mirror)
			)
		)
		(duplicate_pad_numbers_are_jumpers no)
		(fp_poly
			(pts
				(arc
					(start 0.3556 0)
					(mid -0.3556 0)
					(end 0.3556 0)
				)
			)
			(stroke
				(width 0)
				(type default)
			)
			(fill no)
			(layer "B.CrtYd")
		)
		(fp_poly
			(pts
				(arc
					(start 0.6096 0)
					(mid -0.6096 0)
					(end 0.6096 0)
				)
			)
			(stroke
				(width 0)
				(type default)
			)
			(fill no)
			(layer "B.Fab")
		)
		(pad "1" smd circle
			(at 0 0 180)
			(size 0.7112 0.7112)
			(layers "B.Cu" "B.Mask" "B.Paste")
			(net "IOC_GPIO_21")
		)
	)
	(footprint ""
		(layer "B.Cu")
		(at 83.198208 -56.231536)
		(property "Reference" "C29"
			(at 0 0 0)
			(layer "B.SilkS")
			(hide yes)
			(effects
				(font
					(size 1.27 1.27)
				)
				(justify mirror)
			)
		)
		(property "Value" "SC2D2U25V5KX-2-GP"
			(at 0.0762 -6.1214 0)
			(unlocked yes)
			(layer "B.Fab")
			(hide yes)
			(effects
				(font
					(size 1.016 1.016)
					(thickness 0.1524)
				)
				(justify mirror)
			)
		)
		(property "Device Type" "C805H54"
			(at 0.0762 -8.1534 0)
			(unlocked yes)
			(layer "B.Fab")
			(hide yes)
			(effects
				(font
					(size 1.016 1.016)
					(thickness 0.1524)
				)
				(justify mirror)
			)
		)
		(duplicate_pad_numbers_are_jumpers no)
		(fp_line
			(start -0.635 0)
			(end 0.635 0)
			(stroke
				(width 0.508)
				(type default)
			)
			(layer "B.SilkS")
		)
		(fp_rect
			(start 0.9652 1.778)
			(end -0.9652 -1.778)
			(stroke
				(width 0)
				(type default)
			)
			(fill no)
			(layer "B.CrtYd")
		)
		(fp_poly
			(pts
				(xy 0.9652 -1.778) (xy -0.9652 -1.778) (xy -0.9652 1.778) (xy 0.9652 1.778)
			)
			(stroke
				(width 0)
				(type default)
			)
			(fill no)
			(layer "B.Fab")
		)
		(pad "1" smd rect
			(at 0 -0.9652 180)
			(size 1.397 1.143)
			(layers "B.Cu" "B.Mask" "B.Paste")
			(net "P3V3_STBY")
		)
		(pad "2" smd rect
			(at 0 0.9652 180)
			(size 1.397 1.143)
			(layers "B.Cu" "B.Mask" "B.Paste")
			(net "GND")
		)
	)
	(footprint ""
		(layer "B.Cu")
		(at 197.5104 -113.538 180)
		(property "Reference" "C261"
			(at 0 0 0)
			(layer "B.SilkS")
			(hide yes)
			(effects
				(font
					(size 1.27 1.27)
				)
				(justify mirror)
			)
		)
		(property "Value" "SC22U6D3V6KX-2-GP"
			(at 0.0762 -5.1308 180)
			(unlocked yes)
			(layer "B.Fab")
			(hide yes)
			(effects
				(font
					(size 1.016 1.016)
					(thickness 0.1524)
				)
				(justify mirror)
			)
		)
		(property "Device Type" "C1206H71"
			(at 0.127 -6.6548 180)
			(unlocked yes)
			(layer "B.Fab")
			(hide yes)
			(effects
				(font
					(size 1.016 1.016)
					(thickness 0.1524)
				)
				(justify mirror)
			)
		)
		(duplicate_pad_numbers_are_jumpers no)
		(fp_line
			(start 1.016 2.2352)
			(end 1.016 0.8382)
			(stroke
				(width 0.1524)
				(type default)
			)
			(layer "B.SilkS")
		)
		(fp_line
			(start 1.016 -0.8382)
			(end 1.016 -2.2352)
			(stroke
				(width 0.1524)
				(type default)
			)
			(layer "B.SilkS")
		)
		(fp_line
			(start 1.016 -2.2352)
			(end -1.016 -2.2352)
			(stroke
				(width 0.1524)
				(type default)
			)
			(layer "B.SilkS")
		)
		(fp_line
			(start -1.016 2.2352)
			(end 1.016 2.2352)
			(stroke
				(width 0.1524)
				(type default)
			)
			(layer "B.SilkS")
		)
		(fp_line
			(start -1.016 0.8382)
			(end -1.016 2.2352)
			(stroke
				(width 0.1524)
				(type default)
			)
			(layer "B.SilkS")
		)
		(fp_line
			(start -1.016 -2.2352)
			(end -1.016 -0.8382)
			(stroke
				(width 0.1524)
				(type default)
			)
			(layer "B.SilkS")
		)
		(fp_rect
			(start 1.0922 2.3114)
			(end -1.0922 -2.3114)
			(stroke
				(width 0)
				(type default)
			)
			(fill no)
			(layer "B.CrtYd")
		)
		(fp_poly
			(pts
				(xy -1.0922 -2.3114) (xy -1.0922 2.3114) (xy 1.0922 2.3114) (xy 1.0922 -2.3114)
			)
			(stroke
				(width 0)
				(type default)
			)
			(fill no)
			(layer "B.Fab")
		)
		(pad "1" smd rect
			(at 0 -1.397)
			(size 1.651 1.27)
			(layers "B.Cu" "B.Mask" "B.Paste")
			(net "P0V975")
		)
		(pad "2" smd rect
			(at 0 1.397)
			(size 1.651 1.27)
			(layers "B.Cu" "B.Mask" "B.Paste")
			(net "GND")
		)
	)
	(footprint ""
		(layer "B.Cu")
		(at 60.213748 -154.031188 -90)
		(property "Reference" "R394"
			(at 0 0 90)
			(layer "B.SilkS")
			(hide yes)
			(effects
				(font
					(size 1.27 1.27)
				)
				(justify mirror)
			)
		)
		(property "Value" "4K7R2F-GP"
			(at -0.064008 -3.993896 270)
			(unlocked yes)
			(layer "B.Fab")
			(hide yes)
			(effects
				(font
					(size 1.016 1.016)
					(thickness 0.1524)
				)
				(justify mirror)
			)
		)
		(property "Device Type" "R402H16"
			(at -0.064008 -5.517896 270)
			(unlocked yes)
			(layer "B.Fab")
			(hide yes)
			(effects
				(font
					(size 1.016 1.016)
					(thickness 0.1524)
				)
				(justify mirror)
			)
		)
		(duplicate_pad_numbers_are_jumpers no)
		(fp_line
			(start -0.508 -0.9398)
			(end 0.508 -0.9398)
			(stroke
				(width 0.1524)
				(type default)
			)
			(layer "B.SilkS")
		)
		(fp_line
			(start 0.508 -0.9398)
			(end 0.508 0.9398)
			(stroke
				(width 0.1524)
				(type default)
			)
			(layer "B.SilkS")
		)
		(fp_rect
			(start 0.508 0.9398)
			(end -0.508 -0.9398)
			(stroke
				(width 0)
				(type default)
			)
			(fill no)
			(layer "B.CrtYd")
		)
		(fp_rect
			(start 0.508 0.9398)
			(end -0.508 -0.9398)
			(stroke
				(width 0)
				(type default)
			)
			(fill no)
			(layer "B.Fab")
		)
		(pad "1" smd custom
			(at 0 -0.4445 90)
			(size 0.1397 0.1397)
			(layers "B.Cu" "B.Mask" "B.Paste")
			(net "P3V3_STBY")
			(options
				(clearance outline)
				(anchor circle)
			)
			(primitives
				(gr_poly
					(pts
						(arc
							(start -0.1778 0.2794)
							(mid -0.249642 0.249642)
							(end -0.2794 0.1778)
						)
						(arc
							(start -0.2794 -0.1778)
							(mid -0.249642 -0.249642)
							(end -0.1778 -0.2794)
						)
						(arc
							(start 0.1778 -0.2794)
							(mid 0.249642 -0.249642)
							(end 0.2794 -0.1778)
						)
						(arc
							(start 0.2794 0.1778)
							(mid 0.249642 0.249642)
							(end 0.1778 0.2794)
						)
					)
					(width 0)
					(fill yes)
				)
			)
		)
		(pad "2" smd custom
			(at 0 0.4445 90)
			(size 0.1397 0.1397)
			(layers "B.Cu" "B.Mask" "B.Paste")
			(net "MAC2_TXD3")
			(options
				(clearance outline)
				(anchor circle)
			)
			(primitives
				(gr_poly
					(pts
						(arc
							(start -0.1778 0.2794)
							(mid -0.249642 0.249642)
							(end -0.2794 0.1778)
						)
						(arc
							(start -0.2794 -0.1778)
							(mid -0.249642 -0.249642)
							(end -0.1778 -0.2794)
						)
						(arc
							(start 0.1778 -0.2794)
							(mid 0.249642 -0.249642)
							(end 0.2794 -0.1778)
						)
						(arc
							(start 0.2794 0.1778)
							(mid 0.249642 0.249642)
							(end 0.1778 0.2794)
						)
					)
					(width 0)
					(fill yes)
				)
			)
		)
	)
)
